# TIMECARD (Time Appliance Project (Time Card)) — schematic netlist excerpt (pin names and nets, part order shuffled) for the footprints in the layout excerpt that follows; sources: Cadence DE-HDL packaged netlist, KiCad conversion of R4006-B0001-02_R01.brd

C230  CAPACITOR  0.1UF 25V 10%  pkg SMC_0402R_H022  page 31 : \1\ = UNNAMED_515_CAPACITOR_I130_1 ; \2\ = SG
SP63  NULL  pkg DUMMY  page 34
R73  RESISTOR  33OHM 1%  pkg SMC_0402R_H016  page 19 : \1\ = BF_ICP10100_I2C_SCL ; \2\ = R_ICP10100_I2C_SCL

(kicad_pcb
	(version 20260206)
	(generator "pcbnew")
	(generator_version "10.0")
	(general
		(thickness 1.6)
		(legacy_teardrops no)
	)
	(paper "A4")
	(title_block
		(title "timecard-production-celestica-r4006 — R4006-B0001-02_R01.brd")
		(comment 1 "Time Appliance Project (Time Card) / footprints 555-557 of 1113")
	)
	(layers
		(0 "F.Cu" signal "TOP")
		(4 "In1.Cu" signal "L02_GND1")
		(6 "In2.Cu" signal "L03_SIG1")
		(8 "In3.Cu" signal "L04_GND2")
		(10 "In4.Cu" signal "L05_VCC1")
		(12 "In5.Cu" signal "L06_VCC2")
		(14 "In6.Cu" signal "L07_GND3")
		(16 "In7.Cu" signal "L08_SIG2")
		(18 "In8.Cu" signal "L09_GND4")
		(2 "B.Cu" signal "BOTTOM")
		(9 "F.Adhes" user "F.Adhesive")
		(11 "B.Adhes" user "B.Adhesive")
		(13 "F.Paste" user "Package Geometry/Pastemask Top")
		(15 "B.Paste" user "Package Geometry/Pastemask Bottom")
		(5 "F.SilkS" user "Ref Des/Silkscreen Top")
		(7 "B.SilkS" user "Ref Des/Silkscreen Bottom")
		(1 "F.Mask" user "Board Geometry/Soldermask Top")
		(3 "B.Mask" user "Board Geometry/Soldermask Bottom")
		(17 "Dwgs.User" user "User.Drawings")
		(19 "Cmts.User" user "User.Comments")
		(21 "Eco1.User" user "User.Eco1")
		(23 "Eco2.User" user "User.Eco2")
		(25 "Edge.Cuts" user "Board Geometry/Outline")
		(27 "Margin" user)
		(31 "F.CrtYd" user "Package Geometry/Place Bound Top")
		(29 "B.CrtYd" user "Package Geometry/Place Bound Bottom")
		(35 "F.Fab" user "Ref Des/Assembly Top")
		(33 "B.Fab" user "Ref Des/Assembly Bottom")
	)
	(footprint ""
		(layer "F.Cu")
		(at 144.018 -20.1168 180)
		(property "Reference" "C230"
			(at -3.048 1.43383 0)
			(unlocked yes)
			(layer "F.SilkS")
			(effects
				(font
					(size 0.7874 0.5842)
					(thickness 0.1524)
				)
			)
		)
		(property "Value" "VAL*"
			(at 0.0762 2.067306 180)
			(unlocked yes)
			(layer "F.Fab")
			(hide yes)
			(effects
				(font
					(size 0.7874 0.5842)
					(thickness 0.1524)
				)
			)
		)
		(property "Tolerance" "TOL*"
			(at 0.0762 3.032506 180)
			(unlocked yes)
			(layer "Cmts.User")
			(hide yes)
			(effects
				(font
					(size 0.7874 0.5842)
					(thickness 0.1524)
				)
			)
		)
		(property "User Part Number" "PARTNUM*"
			(at 0.1016 4.023106 180)
			(unlocked yes)
			(layer "Cmts.User")
			(hide yes)
			(effects
				(font
					(size 0.7874 0.5842)
					(thickness 0.1524)
				)
			)
		)
		(property "Device Type" "CAPACITOR-G105-0B104-EK,0.1UF,A"
			(at 0.0508 1.127506 180)
			(unlocked yes)
			(layer "F.Fab")
			(hide yes)
			(effects
				(font
					(size 0.7874 0.5842)
					(thickness 0.1524)
				)
			)
		)
		(duplicate_pad_numbers_are_jumpers no)
		(fp_line
			(start 1.143 0.5588)
			(end 1.143 -0.5588)
			(stroke
				(width 0.1)
				(type default)
			)
			(layer "F.SilkS")
		)
		(fp_line
			(start 1.143 -0.5588)
			(end -1.143 -0.5588)
			(stroke
				(width 0.1)
				(type default)
			)
			(layer "F.SilkS")
		)
		(fp_line
			(start -1.143 0.5588)
			(end 1.143 0.5588)
			(stroke
				(width 0.1)
				(type default)
			)
			(layer "F.SilkS")
		)
		(fp_line
			(start -1.143 -0.5588)
			(end -1.143 0.5588)
			(stroke
				(width 0.1)
				(type default)
			)
			(layer "F.SilkS")
		)
		(fp_rect
			(start -1.143 0.5588)
			(end 1.143 -0.5588)
			(stroke
				(width 0)
				(type default)
			)
			(fill no)
			(layer "F.CrtYd")
		)
		(fp_line
			(start 0.508 0.3048)
			(end 0.508 -0.3048)
			(stroke
				(width 0.1)
				(type default)
			)
			(layer "F.Fab")
		)
		(fp_line
			(start 0.508 -0.3048)
			(end -0.508 -0.3048)
			(stroke
				(width 0.1)
				(type default)
			)
			(layer "F.Fab")
		)
		(fp_line
			(start -0.508 0.3048)
			(end 0.508 0.3048)
			(stroke
				(width 0.1)
				(type default)
			)
			(layer "F.Fab")
		)
		(fp_line
			(start -0.508 -0.3048)
			(end -0.508 0.3048)
			(stroke
				(width 0.1)
				(type default)
			)
			(layer "F.Fab")
		)
		(pad "1" smd rect
			(at -0.5334 0 180)
			(size 0.7112 0.6096)
			(layers "F.Cu" "F.Mask" "F.Paste")
			(net "UNNAMED_515_CAPACITOR_I130_1")
		)
		(pad "2" smd rect
			(at 0.5334 0 180)
			(size 0.7112 0.6096)
			(layers "F.Cu" "F.Mask" "F.Paste")
			(net "SG")
		)
		(zone
			(layer "F.Cu")
			(hatch none 0.5)
			(connect_pads
				(clearance 0)
			)
			(min_thickness 0.25)
			(keepout
				(tracks allowed)
				(vias not_allowed)
				(pads allowed)
				(copperpour not_allowed)
				(footprints allowed)
			)
			(placement
				(enabled no)
				(sheetname "")
			)
			(fill
				(thermal_gap 0.5)
				(thermal_bridge_width 0.5)
				(island_removal_mode 0)
			)
			(polygon
				(pts
					(xy 144.0942 -20.4216) (xy 143.9418 -20.4216) (xy 143.9418 -19.812) (xy 144.0942 -19.812)
				)
			)
		)
	)
	(footprint ""
		(layer "F.Cu")
		(at 18.669 -70.866 180)
		(property "Reference" "R73"
			(at -0.635 2.24663 0)
			(unlocked yes)
			(layer "F.SilkS")
			(effects
				(font
					(size 0.7874 0.5842)
					(thickness 0.1524)
				)
			)
		)
		(property "Value" "VAL*"
			(at 0.02032 2.13233 180)
			(unlocked yes)
			(layer "F.Fab")
			(hide yes)
			(effects
				(font
					(size 0.7874 0.5842)
					(thickness 0.1524)
				)
			)
		)
		(property "Tolerance" "TOL*"
			(at 0.044704 3.05435 180)
			(unlocked yes)
			(layer "Cmts.User")
			(hide yes)
			(effects
				(font
					(size 0.7874 0.5842)
					(thickness 0.1524)
				)
			)
		)
		(property "User Part Number" "PARTNUM*"
			(at 0.02032 4.024884 180)
			(unlocked yes)
			(layer "Cmts.User")
			(hide yes)
			(effects
				(font
					(size 0.7874 0.5842)
					(thickness 0.1524)
				)
			)
		)
		(property "Device Type" "RESISTOR-G155-133R0-01,33OHM,1%"
			(at 0.008382 1.210564 180)
			(unlocked yes)
			(layer "F.Fab")
			(hide yes)
			(effects
				(font
					(size 0.7874 0.5842)
					(thickness 0.1524)
				)
			)
		)
		(duplicate_pad_numbers_are_jumpers no)
		(fp_line
			(start 1.143 0.5588)
			(end 1.143 -0.5588)
			(stroke
				(width 0.1)
				(type default)
			)
			(layer "F.SilkS")
		)
		(fp_line
			(start 1.143 -0.5588)
			(end -1.143 -0.5588)
			(stroke
				(width 0.1)
				(type default)
			)
			(layer "F.SilkS")
		)
		(fp_line
			(start -1.143 0.5588)
			(end 1.143 0.5588)
			(stroke
				(width 0.1)
				(type default)
			)
			(layer "F.SilkS")
		)
		(fp_line
			(start -1.143 -0.5588)
			(end -1.143 0.5588)
			(stroke
				(width 0.1)
				(type default)
			)
			(layer "F.SilkS")
		)
		(fp_rect
			(start -1.143 0.5588)
			(end 1.143 -0.5588)
			(stroke
				(width 0)
				(type default)
			)
			(fill no)
			(layer "F.CrtYd")
		)
		(fp_line
			(start 0.508 0.3048)
			(end 0.508 -0.3048)
			(stroke
				(width 0.1)
				(type default)
			)
			(layer "F.Fab")
		)
		(fp_line
			(start 0.508 -0.3048)
			(end -0.508 -0.3048)
			(stroke
				(width 0.1)
				(type default)
			)
			(layer "F.Fab")
		)
		(fp_line
			(start -0.508 0.3048)
			(end 0.508 0.3048)
			(stroke
				(width 0.1)
				(type default)
			)
			(layer "F.Fab")
		)
		(fp_line
			(start -0.508 -0.3048)
			(end -0.508 0.3048)
			(stroke
				(width 0.1)
				(type default)
			)
			(layer "F.Fab")
		)
		(pad "1" smd rect
			(at -0.5334 0 180)
			(size 0.7112 0.6096)
			(layers "F.Cu" "F.Mask" "F.Paste")
			(net "BF_ICP10100_I2C_SCL")
		)
		(pad "2" smd rect
			(at 0.5334 0 180)
			(size 0.7112 0.6096)
			(layers "F.Cu" "F.Mask" "F.Paste")
			(net "R_ICP10100_I2C_SCL")
		)
		(zone
			(layer "F.Cu")
			(hatch none 0.5)
			(connect_pads
				(clearance 0)
			)
			(min_thickness 0.25)
			(keepout
				(tracks allowed)
				(vias not_allowed)
				(pads allowed)
				(copperpour not_allowed)
				(footprints allowed)
			)
			(placement
				(enabled no)
				(sheetname "")
			)
			(fill
				(thermal_gap 0.5)
				(thermal_bridge_width 0.5)
				(island_removal_mode 0)
			)
			(polygon
				(pts
					(xy 18.7452 -71.1708) (xy 18.5928 -71.1708) (xy 18.5928 -70.5612) (xy 18.7452 -70.5612)
				)
			)
		)
	)
	(footprint ""
		(layer "F.Cu")
		(at 46.228 -131.064)
		(property "Reference" "SP63"
			(at 0 0 0)
			(layer "F.SilkS")
			(hide yes)
			(effects
				(font
					(size 1.27 1.27)
				)
			)
		)
		(property "Value" ""
			(at 0 0 0)
			(layer "F.Fab")
			(effects
				(font
					(size 1.27 1.27)
				)
			)
		)
		(duplicate_pad_numbers_are_jumpers no)
	)
)
